(kicad_pcb
	(version 20260206)
	(generator "pcbnew")
	(generator_version "10.0")
	(general
		(thickness 1.6)
		(legacy_teardrops no)
	)
	(paper "A4")
	(title_block
		(title "01162023_DA0F0TEBIF0_F0T_Expander_BD_F_brd_V02_OCP.brd")
		(comment 1 "Grand Teton / footprints 6225-6231 of 9728")
	)
	(layers
		(0 "F.Cu" signal "TOP")
		(4 "In1.Cu" signal "GND")
		(6 "In2.Cu" signal "VCC")
		(8 "In3.Cu" signal "VCC1")
		(10 "In4.Cu" signal "GND1")
		(12 "In5.Cu" signal "IN1")
		(14 "In6.Cu" signal "GND2")
		(16 "In7.Cu" signal "IN2")
		(18 "In8.Cu" signal "GND3")
		(20 "In9.Cu" signal "IN3")
		(22 "In10.Cu" signal "GND4")
		(24 "In11.Cu" signal "IN4")
		(26 "In12.Cu" signal "GND5")
		(28 "In13.Cu" signal "IN5")
		(30 "In14.Cu" signal "GND6")
		(32 "In15.Cu" signal "IN6")
		(34 "In16.Cu" signal "GND7")
		(2 "B.Cu" signal "BOTTOM")
		(9 "F.Adhes" user "F.Adhesive")
		(11 "B.Adhes" user "B.Adhesive")
		(13 "F.Paste" user "Package Geometry/Pastemask Top")
		(15 "B.Paste" user "Package Geometry/Pastemask Bottom")
		(5 "F.SilkS" user "Ref Des/Silkscreen Top")
		(7 "B.SilkS" user "Ref Des/Silkscreen Bottom")
		(1 "F.Mask" user "Board Geometry/Soldermask Top")
		(3 "B.Mask" user "Board Geometry/Soldermask Bottom")
		(17 "Dwgs.User" user "User.Drawings")
		(19 "Cmts.User" user "User.Comments")
		(21 "Eco1.User" user "User.Eco1")
		(23 "Eco2.User" user "User.Eco2")
		(25 "Edge.Cuts" user "Board Geometry/Outline")
		(27 "Margin" user)
		(31 "F.CrtYd" user "Package Geometry/Place Bound Top")
		(29 "B.CrtYd" user "Package Geometry/Place Bound Bottom")
		(35 "F.Fab" user "Ref Des/Assembly Top")
		(33 "B.Fab" user "Ref Des/Assembly Bottom")
	)
	(footprint ""
		(layer "F.Cu")
		(at 153.650442 -252.356874 -90)
		(property "Reference" "R1299"
			(at 0 0 270)
			(layer "F.SilkS")
			(hide yes)
			(effects
				(font
					(size 1.27 1.27)
				)
			)
		)
		(property "Value" ""
			(at 0 0 270)
			(layer "F.Fab")
			(effects
				(font
					(size 1.27 1.27)
				)
			)
		)
		(duplicate_pad_numbers_are_jumpers no)
		(fp_line
			(start -0.7874 0.4064)
			(end -0.7874 -0.4064)
			(stroke
				(width 0.1524)
				(type default)
			)
			(layer "F.SilkS")
		)
		(fp_line
			(start 0.7874 0.4064)
			(end -0.7874 0.4064)
			(stroke
				(width 0.1524)
				(type default)
			)
			(layer "F.SilkS")
		)
		(fp_line
			(start -0.7874 -0.4064)
			(end 0.7874 -0.4064)
			(stroke
				(width 0.1524)
				(type default)
			)
			(layer "F.SilkS")
		)
		(fp_line
			(start 0.7874 -0.4064)
			(end 0.7874 0.4064)
			(stroke
				(width 0.1524)
				(type default)
			)
			(layer "F.SilkS")
		)
		(fp_line
			(start -0.67945 0.3048)
			(end -0.67945 -0.305054)
			(stroke
				(width 0.1)
				(type default)
			)
			(layer "F.Fab")
		)
		(fp_line
			(start -0.12065 0.3048)
			(end -0.67945 0.3048)
			(stroke
				(width 0.1)
				(type default)
			)
			(layer "F.Fab")
		)
		(fp_line
			(start 0.120396 0.3048)
			(end 0.120396 0.2794)
			(stroke
				(width 0.1)
				(type default)
			)
			(layer "F.Fab")
		)
		(fp_line
			(start 0.67945 0.3048)
			(end 0.120396 0.3048)
			(stroke
				(width 0.1)
				(type default)
			)
			(layer "F.Fab")
		)
		(fp_line
			(start -0.12065 0.2794)
			(end -0.12065 0.3048)
			(stroke
				(width 0.1)
				(type default)
			)
			(layer "F.Fab")
		)
		(fp_line
			(start 0.120396 0.2794)
			(end -0.12065 0.2794)
			(stroke
				(width 0.1)
				(type default)
			)
			(layer "F.Fab")
		)
		(fp_line
			(start -0.12065 -0.2794)
			(end 0.12065 -0.2794)
			(stroke
				(width 0.1)
				(type default)
			)
			(layer "F.Fab")
		)
		(fp_line
			(start 0.12065 -0.2794)
			(end 0.12065 -0.3048)
			(stroke
				(width 0.1)
				(type default)
			)
			(layer "F.Fab")
		)
		(fp_line
			(start 0.12065 -0.3048)
			(end 0.67945 -0.3048)
			(stroke
				(width 0.1)
				(type default)
			)
			(layer "F.Fab")
		)
		(fp_line
			(start 0.67945 -0.3048)
			(end 0.67945 0.3048)
			(stroke
				(width 0.1)
				(type default)
			)
			(layer "F.Fab")
		)
		(fp_line
			(start -0.67945 -0.305054)
			(end -0.12065 -0.305054)
			(stroke
				(width 0.1)
				(type default)
			)
			(layer "F.Fab")
		)
		(fp_line
			(start -0.12065 -0.305054)
			(end -0.12065 -0.2794)
			(stroke
				(width 0.1)
				(type default)
			)
			(layer "F.Fab")
		)
		(pad "1" smd circle
			(at -0.40005 0 270)
			(size 0 0)
			(layers "F.Cu" "F.Mask" "F.Paste")
			(net "GND")
		)
		(pad "2" smd circle
			(at 0.40005 0 270)
			(size 0 0)
			(layers "F.Cu" "F.Mask" "F.Paste")
			(net "PEX1_MODE_SEL10")
		)
	)
	(footprint ""
		(layer "F.Cu")
		(at 124.07519 -105.134918 90)
		(property "Reference" "R5827"
			(at 0 0 90)
			(layer "F.SilkS")
			(hide yes)
			(effects
				(font
					(size 1.27 1.27)
				)
			)
		)
		(property "Value" ""
			(at 0 0 90)
			(layer "F.Fab")
			(effects
				(font
					(size 1.27 1.27)
				)
			)
		)
		(duplicate_pad_numbers_are_jumpers no)
		(fp_line
			(start 0.7874 -0.4064)
			(end 0.7874 0.4064)
			(stroke
				(width 0.1524)
				(type default)
			)
			(layer "F.SilkS")
		)
		(fp_line
			(start -0.7874 -0.4064)
			(end 0.7874 -0.4064)
			(stroke
				(width 0.1524)
				(type default)
			)
			(layer "F.SilkS")
		)
		(fp_line
			(start 0.7874 0.4064)
			(end -0.7874 0.4064)
			(stroke
				(width 0.1524)
				(type default)
			)
			(layer "F.SilkS")
		)
		(fp_line
			(start -0.7874 0.4064)
			(end -0.7874 -0.4064)
			(stroke
				(width 0.1524)
				(type default)
			)
			(layer "F.SilkS")
		)
		(fp_line
			(start -0.12065 -0.305054)
			(end -0.12065 -0.2794)
			(stroke
				(width 0.1)
				(type default)
			)
			(layer "F.Fab")
		)
		(fp_line
			(start -0.67945 -0.305054)
			(end -0.12065 -0.305054)
			(stroke
				(width 0.1)
				(type default)
			)
			(layer "F.Fab")
		)
		(fp_line
			(start 0.67945 -0.3048)
			(end 0.67945 0.3048)
			(stroke
				(width 0.1)
				(type default)
			)
			(layer "F.Fab")
		)
		(fp_line
			(start 0.12065 -0.3048)
			(end 0.67945 -0.3048)
			(stroke
				(width 0.1)
				(type default)
			)
			(layer "F.Fab")
		)
		(fp_line
			(start 0.12065 -0.2794)
			(end 0.12065 -0.3048)
			(stroke
				(width 0.1)
				(type default)
			)
			(layer "F.Fab")
		)
		(fp_line
			(start -0.12065 -0.2794)
			(end 0.12065 -0.2794)
			(stroke
				(width 0.1)
				(type default)
			)
			(layer "F.Fab")
		)
		(fp_line
			(start 0.120396 0.2794)
			(end -0.12065 0.2794)
			(stroke
				(width 0.1)
				(type default)
			)
			(layer "F.Fab")
		)
		(fp_line
			(start -0.12065 0.2794)
			(end -0.12065 0.3048)
			(stroke
				(width 0.1)
				(type default)
			)
			(layer "F.Fab")
		)
		(fp_line
			(start 0.67945 0.3048)
			(end 0.120396 0.3048)
			(stroke
				(width 0.1)
				(type default)
			)
			(layer "F.Fab")
		)
		(fp_line
			(start 0.120396 0.3048)
			(end 0.120396 0.2794)
			(stroke
				(width 0.1)
				(type default)
			)
			(layer "F.Fab")
		)
		(fp_line
			(start -0.12065 0.3048)
			(end -0.67945 0.3048)
			(stroke
				(width 0.1)
				(type default)
			)
			(layer "F.Fab")
		)
		(fp_line
			(start -0.67945 0.3048)
			(end -0.67945 -0.305054)
			(stroke
				(width 0.1)
				(type default)
			)
			(layer "F.Fab")
		)
		(pad "1" smd circle
			(at -0.40005 0 90)
			(size 0 0)
			(layers "F.Cu" "F.Mask" "F.Paste")
			(net "P3V3_AUX")
		)
		(pad "2" smd circle
			(at 0.40005 0 90)
			(size 0 0)
			(layers "F.Cu" "F.Mask" "F.Paste")
			(net "P3V3_PG_G2")
		)
	)
	(footprint ""
		(layer "F.Cu")
		(at 359.156 -185.166)
		(property "Reference" "R4601"
			(at 0 0 0)
			(layer "F.SilkS")
			(hide yes)
			(effects
				(font
					(size 1.27 1.27)
				)
			)
		)
		(property "Value" ""
			(at 0 0 0)
			(layer "F.Fab")
			(effects
				(font
					(size 1.27 1.27)
				)
			)
		)
		(duplicate_pad_numbers_are_jumpers no)
		(fp_line
			(start -0.7874 -0.4064)
			(end 0.7874 -0.4064)
			(stroke
				(width 0.1524)
				(type default)
			)
			(layer "F.SilkS")
		)
		(fp_line
			(start -0.7874 0.4064)
			(end -0.7874 -0.4064)
			(stroke
				(width 0.1524)
				(type default)
			)
			(layer "F.SilkS")
		)
		(fp_line
			(start 0.7874 -0.4064)
			(end 0.7874 0.4064)
			(stroke
				(width 0.1524)
				(type default)
			)
			(layer "F.SilkS")
		)
		(fp_line
			(start 0.7874 0.4064)
			(end -0.7874 0.4064)
			(stroke
				(width 0.1524)
				(type default)
			)
			(layer "F.SilkS")
		)
		(fp_line
			(start -0.67945 -0.305054)
			(end -0.12065 -0.305054)
			(stroke
				(width 0.1)
				(type default)
			)
			(layer "F.Fab")
		)
		(fp_line
			(start -0.67945 0.3048)
			(end -0.67945 -0.305054)
			(stroke
				(width 0.1)
				(type default)
			)
			(layer "F.Fab")
		)
		(fp_line
			(start -0.12065 -0.305054)
			(end -0.12065 -0.2794)
			(stroke
				(width 0.1)
				(type default)
			)
			(layer "F.Fab")
		)
		(fp_line
			(start -0.12065 -0.2794)
			(end 0.12065 -0.2794)
			(stroke
				(width 0.1)
				(type default)
			)
			(layer "F.Fab")
		)
		(fp_line
			(start -0.12065 0.2794)
			(end -0.12065 0.3048)
			(stroke
				(width 0.1)
				(type default)
			)
			(layer "F.Fab")
		)
		(fp_line
			(start -0.12065 0.3048)
			(end -0.67945 0.3048)
			(stroke
				(width 0.1)
				(type default)
			)
			(layer "F.Fab")
		)
		(fp_line
			(start 0.120396 0.2794)
			(end -0.12065 0.2794)
			(stroke
				(width 0.1)
				(type default)
			)
			(layer "F.Fab")
		)
		(fp_line
			(start 0.120396 0.3048)
			(end 0.120396 0.2794)
			(stroke
				(width 0.1)
				(type default)
			)
			(layer "F.Fab")
		)
		(fp_line
			(start 0.12065 -0.3048)
			(end 0.67945 -0.3048)
			(stroke
				(width 0.1)
				(type default)
			)
			(layer "F.Fab")
		)
		(fp_line
			(start 0.12065 -0.2794)
			(end 0.12065 -0.3048)
			(stroke
				(width 0.1)
				(type default)
			)
			(layer "F.Fab")
		)
		(fp_line
			(start 0.67945 -0.3048)
			(end 0.67945 0.3048)
			(stroke
				(width 0.1)
				(type default)
			)
			(layer "F.Fab")
		)
		(fp_line
			(start 0.67945 0.3048)
			(end 0.120396 0.3048)
			(stroke
				(width 0.1)
				(type default)
			)
			(layer "F.Fab")
		)
		(pad "1" smd circle
			(at -0.40005 0)
			(size 0 0)
			(layers "F.Cu" "F.Mask" "F.Paste")
			(net "P3V3_AUX")
		)
		(pad "2" smd circle
			(at 0.40005 0)
			(size 0 0)
			(layers "F.Cu" "F.Mask" "F.Paste")
			(net "SSD3_PEX_PWR_EN_R")
		)
	)
	(footprint ""
		(layer "F.Cu")
		(at 364.945168 -395.463014 -90)
		(property "Reference" "R6772"
			(at 0 0 270)
			(layer "F.SilkS")
			(hide yes)
			(effects
				(font
					(size 1.27 1.27)
				)
			)
		)
		(property "Value" ""
			(at 0 0 270)
			(layer "F.Fab")
			(effects
				(font
					(size 1.27 1.27)
				)
			)
		)
		(duplicate_pad_numbers_are_jumpers no)
		(fp_line
			(start -0.7874 0.4064)
			(end -0.7874 -0.4064)
			(stroke
				(width 0.1524)
				(type default)
			)
			(layer "F.SilkS")
		)
		(fp_line
			(start 0.7874 0.4064)
			(end -0.7874 0.4064)
			(stroke
				(width 0.1524)
				(type default)
			)
			(layer "F.SilkS")
		)
		(fp_line
			(start -0.7874 -0.4064)
			(end 0.7874 -0.4064)
			(stroke
				(width 0.1524)
				(type default)
			)
			(layer "F.SilkS")
		)
		(fp_line
			(start 0.7874 -0.4064)
			(end 0.7874 0.4064)
			(stroke
				(width 0.1524)
				(type default)
			)
			(layer "F.SilkS")
		)
		(fp_line
			(start -0.67945 0.3048)
			(end -0.67945 -0.305054)
			(stroke
				(width 0.1)
				(type default)
			)
			(layer "F.Fab")
		)
		(fp_line
			(start -0.12065 0.3048)
			(end -0.67945 0.3048)
			(stroke
				(width 0.1)
				(type default)
			)
			(layer "F.Fab")
		)
		(fp_line
			(start 0.120396 0.3048)
			(end 0.120396 0.2794)
			(stroke
				(width 0.1)
				(type default)
			)
			(layer "F.Fab")
		)
		(fp_line
			(start 0.67945 0.3048)
			(end 0.120396 0.3048)
			(stroke
				(width 0.1)
				(type default)
			)
			(layer "F.Fab")
		)
		(fp_line
			(start -0.12065 0.2794)
			(end -0.12065 0.3048)
			(stroke
				(width 0.1)
				(type default)
			)
			(layer "F.Fab")
		)
		(fp_line
			(start 0.120396 0.2794)
			(end -0.12065 0.2794)
			(stroke
				(width 0.1)
				(type default)
			)
			(layer "F.Fab")
		)
		(fp_line
			(start -0.12065 -0.2794)
			(end 0.12065 -0.2794)
			(stroke
				(width 0.1)
				(type default)
			)
			(layer "F.Fab")
		)
		(fp_line
			(start 0.12065 -0.2794)
			(end 0.12065 -0.3048)
			(stroke
				(width 0.1)
				(type default)
			)
			(layer "F.Fab")
		)
		(fp_line
			(start 0.12065 -0.3048)
			(end 0.67945 -0.3048)
			(stroke
				(width 0.1)
				(type default)
			)
			(layer "F.Fab")
		)
		(fp_line
			(start 0.67945 -0.3048)
			(end 0.67945 0.3048)
			(stroke
				(width 0.1)
				(type default)
			)
			(layer "F.Fab")
		)
		(fp_line
			(start -0.67945 -0.305054)
			(end -0.12065 -0.305054)
			(stroke
				(width 0.1)
				(type default)
			)
			(layer "F.Fab")
		)
		(fp_line
			(start -0.12065 -0.305054)
			(end -0.12065 -0.2794)
			(stroke
				(width 0.1)
				(type default)
			)
			(layer "F.Fab")
		)
		(pad "1" smd circle
			(at -0.40005 0 270)
			(size 0 0)
			(layers "F.Cu" "F.Mask" "F.Paste")
			(net "PRSNT_SWB_B1_N")
		)
		(pad "2" smd circle
			(at 0.40005 0 270)
			(size 0 0)
			(layers "F.Cu" "F.Mask" "F.Paste")
			(net "GND")
		)
	)
	(footprint ""
		(layer "F.Cu")
		(at 115.860068 -350.098614 90)
		(property "Reference" "C343"
			(at 0 0 90)
			(layer "F.SilkS")
			(hide yes)
			(effects
				(font
					(size 1.27 1.27)
				)
			)
		)
		(property "Value" ""
			(at 0 0 90)
			(layer "F.Fab")
			(effects
				(font
					(size 1.27 1.27)
				)
			)
		)
		(duplicate_pad_numbers_are_jumpers no)
		(fp_line
			(start 0.299974 -0.150114)
			(end 0.299974 0.150114)
			(stroke
				(width 0.1)
				(type default)
			)
			(layer "F.Fab")
		)
		(fp_line
			(start -0.299974 -0.150114)
			(end 0.299974 -0.150114)
			(stroke
				(width 0.1)
				(type default)
			)
			(layer "F.Fab")
		)
		(fp_line
			(start 0.299974 0.150114)
			(end -0.299974 0.150114)
			(stroke
				(width 0.1)
				(type default)
			)
			(layer "F.Fab")
		)
		(fp_line
			(start -0.299974 0.150114)
			(end -0.299974 -0.150114)
			(stroke
				(width 0.1)
				(type default)
			)
			(layer "F.Fab")
		)
		(pad "1" smd rect
			(at -0.2667 0 90)
			(size 0.3048 0.381)
			(layers "F.Cu" "F.Mask" "F.Paste")
			(net "P5E_PEX1_STN6_TX_DN<110>")
		)
		(pad "2" smd rect
			(at 0.2667 0 90)
			(size 0.3048 0.381)
			(layers "F.Cu" "F.Mask" "F.Paste")
			(net "P5E_PEX1_STN6_TX_C_DN<110>")
		)
	)
	(footprint ""
		(layer "F.Cu")
		(at 10.11047 -126.995428 180)
		(property "Reference" "PC458"
			(at 0 0 180)
			(layer "F.SilkS")
			(hide yes)
			(effects
				(font
					(size 1.27 1.27)
				)
			)
		)
		(property "Value" ""
			(at 0 0 180)
			(layer "F.Fab")
			(effects
				(font
					(size 1.27 1.27)
				)
			)
		)
		(duplicate_pad_numbers_are_jumpers no)
		(fp_line
			(start 0.7874 0.4064)
			(end -0.7874 0.4064)
			(stroke
				(width 0.1524)
				(type default)
			)
			(layer "F.SilkS")
		)
		(fp_line
			(start 0.7874 -0.4064)
			(end 0.7874 0.4064)
			(stroke
				(width 0.1524)
				(type default)
			)
			(layer "F.SilkS")
		)
		(fp_line
			(start -0.7874 0.4064)
			(end -0.7874 -0.4064)
			(stroke
				(width 0.1524)
				(type default)
			)
			(layer "F.SilkS")
		)
		(fp_line
			(start -0.7874 -0.4064)
			(end 0.7874 -0.4064)
			(stroke
				(width 0.1524)
				(type default)
			)
			(layer "F.SilkS")
		)
		(fp_line
			(start 0.67945 0.3048)
			(end 0.120396 0.3048)
			(stroke
				(width 0.1)
				(type default)
			)
			(layer "F.Fab")
		)
		(fp_line
			(start 0.67945 -0.3048)
			(end 0.67945 0.3048)
			(stroke
				(width 0.1)
				(type default)
			)
			(layer "F.Fab")
		)
		(fp_line
			(start 0.12065 -0.2794)
			(end 0.12065 -0.3048)
			(stroke
				(width 0.1)
				(type default)
			)
			(layer "F.Fab")
		)
		(fp_line
			(start 0.12065 -0.3048)
			(end 0.67945 -0.3048)
			(stroke
				(width 0.1)
				(type default)
			)
			(layer "F.Fab")
		)
		(fp_line
			(start 0.120396 0.3048)
			(end 0.120396 0.2794)
			(stroke
				(width 0.1)
				(type default)
			)
			(layer "F.Fab")
		)
		(fp_line
			(start 0.120396 0.2794)
			(end -0.12065 0.2794)
			(stroke
				(width 0.1)
				(type default)
			)
			(layer "F.Fab")
		)
		(fp_line
			(start -0.12065 0.3048)
			(end -0.67945 0.3048)
			(stroke
				(width 0.1)
				(type default)
			)
			(layer "F.Fab")
		)
		(fp_line
			(start -0.12065 0.2794)
			(end -0.12065 0.3048)
			(stroke
				(width 0.1)
				(type default)
			)
			(layer "F.Fab")
		)
		(fp_line
			(start -0.12065 -0.2794)
			(end 0.12065 -0.2794)
			(stroke
				(width 0.1)
				(type default)
			)
			(layer "F.Fab")
		)
		(fp_line
			(start -0.12065 -0.305054)
			(end -0.12065 -0.2794)
			(stroke
				(width 0.1)
				(type default)
			)
			(layer "F.Fab")
		)
		(fp_line
			(start -0.67945 0.3048)
			(end -0.67945 -0.305054)
			(stroke
				(width 0.1)
				(type default)
			)
			(layer "F.Fab")
		)
		(fp_line
			(start -0.67945 -0.305054)
			(end -0.12065 -0.305054)
			(stroke
				(width 0.1)
				(type default)
			)
			(layer "F.Fab")
		)
		(pad "1" smd circle
			(at -0.40005 0 180)
			(size 0 0)
			(layers "F.Cu" "F.Mask" "F.Paste")
			(net "P3V3_NIC0_SS")
		)
		(pad "2" smd circle
			(at 0.40005 0 180)
			(size 0 0)
			(layers "F.Cu" "F.Mask" "F.Paste")
			(net "GND")
		)
	)
	(footprint ""
		(layer "F.Cu")
		(at 10.530586 -146.099276 180)
		(property "Reference" "PC600"
			(at 0 0 180)
			(layer "F.SilkS")
			(hide yes)
			(effects
				(font
					(size 1.27 1.27)
				)
			)
		)
		(property "Value" ""
			(at 0 0 180)
			(layer "F.Fab")
			(effects
				(font
					(size 1.27 1.27)
				)
			)
		)
		(duplicate_pad_numbers_are_jumpers no)
		(fp_line
			(start 1.524 0.762)
			(end -1.524 0.762)
			(stroke
				(width 0.1524)
				(type default)
			)
			(layer "F.SilkS")
		)
		(fp_line
			(start 1.524 -0.762)
			(end 1.524 0.762)
			(stroke
				(width 0.1524)
				(type default)
			)
			(layer "F.SilkS")
		)
		(fp_line
			(start -1.524 0.762)
			(end -1.524 -0.762)
			(stroke
				(width 0.1524)
				(type default)
			)
			(layer "F.SilkS")
		)
		(fp_line
			(start -1.524 -0.762)
			(end 1.524 -0.762)
			(stroke
				(width 0.1524)
				(type default)
			)
			(layer "F.SilkS")
		)
		(fp_line
			(start 1.1049 0.724916)
			(end 1.1049 -0.724916)
			(stroke
				(width 0.1)
				(type default)
			)
			(layer "F.Fab")
		)
		(fp_line
			(start 1.1049 -0.724916)
			(end -1.1049 -0.724916)
			(stroke
				(width 0.1)
				(type default)
			)
			(layer "F.Fab")
		)
		(fp_line
			(start -1.1049 0.724916)
			(end 1.1049 0.724916)
			(stroke
				(width 0.1)
				(type default)
			)
			(layer "F.Fab")
		)
		(fp_line
			(start -1.1049 -0.724916)
			(end -1.1049 0.724916)
			(stroke
				(width 0.1)
				(type default)
			)
			(layer "F.Fab")
		)
		(pad "1" smd rect
			(at -0.889 0)
			(size 1.016 1.27)
			(layers "F.Cu" "F.Mask" "F.Paste")
			(net "P12V_NIC0_R")
		)
		(pad "2" smd rect
			(at 0.889 0)
			(size 1.016 1.27)
			(layers "F.Cu" "F.Mask" "F.Paste")
			(net "GND")
		)
	)
)
